(kicad_sch
	(version 20250114)
	(generator "eeschema")
	(generator_version "9.0")
	(paper "A3")
	(title_block
		(title "Artix - Datacenter Secure Control Module (DC-SCM)")
		(date "2024-11-06")
		(rev "1.1.3")
	)
	(text "Artix - Datacenter Secure Control Module (DC-SCM)"
		(exclude_from_sim no)
		(at 146.685 38.735 0)
		(effects
			(font
				(size 2.9972 2.9972)
				(thickness 0.5994)
				(bold yes)
			)
			(justify left bottom)
		)
	)
	(no_connect
		(at 337.82 182.88)
	)
	(no_connect
		(at 337.82 194.31)
	)
	(symbol
		(lib_id "antmicroMechanicalParts:MP_Pad5.5mm_Drill2.9mm")
		(at 337.82 182.88 0)
		(mirror y)
		(unit 1)
		(exclude_from_sim no)
		(in_bom no)
		(on_board yes)
		(dnp no)
		(fields_autoplaced yes)
		(property "Reference" "MP1"
			(at 332.74 175.26 0)
			(effects
				(font
					(size 1.27 1.27)
				)
			)
		)
		(property "Value" "MP_Pad5.5mm_Drill2.9mm"
			(at 332.74 177.8 0)
			(effects
				(font
					(size 1.27 1.27)
					(thickness 0.15)
				)
			)
		)
		(property "Footprint" "antmicro-footprints:MP_Pad5.5mm_Drill2.9mm"
			(at 322.58 193.04 0)
			(effects
				(font
					(size 1.27 1.27)
					(thickness 0.15)
				)
				(justify left bottom)
				(hide yes)
			)
		)
		(property "Datasheet" ""
			(at 320.98 198.45 0)
			(effects
				(font
					(size 1.27 1.27)
					(thickness 0.15)
				)
				(justify left bottom)
				(hide yes)
			)
		)
		(property "Description" "PCB mounting point"
			(at 337.82 182.88 0)
			(effects
				(font
					(size 1.27 1.27)
				)
				(hide yes)
			)
		)
		(property "Author" "Antmicro"
			(at 322.58 198.12 0)
			(effects
				(font
					(size 1.27 1.27)
					(thickness 0.15)
				)
				(justify left bottom)
				(hide yes)
			)
		)
		(property "License" "Apache-2.0"
			(at 322.58 200.66 0)
			(effects
				(font
					(size 1.27 1.27)
					(thickness 0.15)
				)
				(justify left bottom)
				(hide yes)
			)
		)
		(pin "1"
		)
		(instances
			(project "artix-dc-scm"
				(path ""
					(reference "MP1")
					(unit 1)
				)
			)
		)
	)
	(symbol
		(lib_id "antmicroMechanicalParts:MP_Pad5.5mm_Drill2.9mm")
		(at 337.82 194.31 0)
		(mirror y)
		(unit 1)
		(exclude_from_sim no)
		(in_bom no)
		(on_board yes)
		(dnp no)
		(fields_autoplaced yes)
		(property "Reference" "MP2"
			(at 332.74 186.69 0)
			(effects
				(font
					(size 1.27 1.27)
				)
			)
		)
		(property "Value" "MP_Pad5.5mm_Drill2.9mm"
			(at 332.74 189.23 0)
			(effects
				(font
					(size 1.27 1.27)
					(thickness 0.15)
				)
			)
		)
		(property "Footprint" "antmicro-footprints:MP_Pad5.5mm_Drill2.9mm"
			(at 322.58 204.47 0)
			(effects
				(font
					(size 1.27 1.27)
					(thickness 0.15)
				)
				(justify left bottom)
				(hide yes)
			)
		)
		(property "Datasheet" ""
			(at 320.98 209.88 0)
			(effects
				(font
					(size 1.27 1.27)
					(thickness 0.15)
				)
				(justify left bottom)
				(hide yes)
			)
		)
		(property "Description" "PCB mounting point"
			(at 337.82 194.31 0)
			(effects
				(font
					(size 1.27 1.27)
				)
				(hide yes)
			)
		)
		(property "Author" "Antmicro"
			(at 322.58 209.55 0)
			(effects
				(font
					(size 1.27 1.27)
					(thickness 0.15)
				)
				(justify left bottom)
				(hide yes)
			)
		)
		(property "License" "Apache-2.0"
			(at 322.58 212.09 0)
			(effects
				(font
					(size 1.27 1.27)
					(thickness 0.15)
				)
				(justify left bottom)
				(hide yes)
			)
		)
		(pin "1"
		)
		(instances
			(project "artix-dc-scm"
				(path ""
					(reference "MP2")
					(unit 1)
				)
			)
		)
	)
	(sheet
		(at 114.3 166.37)
		(size 27.94 19.05)
		(exclude_from_sim no)
		(in_bom yes)
		(on_board yes)
		(dnp no)
		(fields_autoplaced yes)
		(stroke
			(width 0)
			(type solid)
		)
		(fill
			(color 0 0 0 0.0000)
		)
		(property "Sheetname" "PCIe-connector"
			(at 114.3 165.6584 0)
			(effects
				(font
					(size 1.27 1.27)
				)
				(justify left bottom)
			)
		)
		(property "Sheetfile" "pcie-conn.kicad_sch"
			(at 114.3 186.0046 0)
			(effects
				(font
					(size 1.27 1.27)
				)
				(justify left top)
			)
		)
		(instances
			(project "artix-dc-scm"
				(path ""
					(page "4")
				)
			)
		)
	)
	(sheet
		(at 289.56 166.37)
		(size 27.94 19.05)
		(exclude_from_sim no)
		(in_bom yes)
		(on_board yes)
		(dnp no)
		(fields_autoplaced yes)
		(stroke
			(width 0)
			(type solid)
		)
		(fill
			(color 0 0 0 0.0000)
		)
		(property "Sheetname" "Power supply"
			(at 289.56 165.6584 0)
			(effects
				(font
					(size 1.27 1.27)
				)
				(justify left bottom)
			)
		)
		(property "Sheetfile" "power-supply.kicad_sch"
			(at 289.56 186.0046 0)
			(effects
				(font
					(size 1.27 1.27)
				)
				(justify left top)
			)
		)
		(instances
			(project "artix-dc-scm"
				(path ""
					(page "10")
				)
			)
		)
	)
	(sheet
		(at 80.01 196.85)
		(size 38.1 25.4)
		(exclude_from_sim no)
		(in_bom yes)
		(on_board yes)
		(dnp no)
		(fields_autoplaced yes)
		(stroke
			(width 0)
			(type solid)
		)
		(fill
			(color 0 0 0 0.0000)
		)
		(property "Sheetname" "FPGA power supply"
			(at 80.01 196.1384 0)
			(effects
				(font
					(size 1.27 1.27)
				)
				(justify left bottom)
			)
		)
		(property "Sheetfile" "fpga-power-supply.kicad_sch"
			(at 80.01 222.8346 0)
			(effects
				(font
					(size 1.27 1.27)
				)
				(justify left top)
			)
		)
		(instances
			(project "artix-dc-scm"
				(path ""
					(page "3")
				)
			)
		)
	)
	(sheet
		(at 130.81 196.85)
		(size 38.1 25.4)
		(exclude_from_sim no)
		(in_bom yes)
		(on_board yes)
		(dnp no)
		(fields_autoplaced yes)
		(stroke
			(width 0)
			(type solid)
		)
		(fill
			(color 0 0 0 0.0000)
		)
		(property "Sheetname" "FPGA banks 13-16"
			(at 130.81 196.1384 0)
			(effects
				(font
					(size 1.27 1.27)
				)
				(justify left bottom)
			)
		)
		(property "Sheetfile" "fpga-banks-13-16.kicad_sch"
			(at 130.81 222.8346 0)
			(effects
				(font
					(size 1.27 1.27)
				)
				(justify left top)
			)
		)
		(instances
			(project "artix-dc-scm"
				(path ""
					(page "5")
				)
			)
		)
	)
	(sheet
		(at 256.54 166.37)
		(size 25.4 17.78)
		(exclude_from_sim no)
		(in_bom yes)
		(on_board yes)
		(dnp no)
		(fields_autoplaced yes)
		(stroke
			(width 0)
			(type solid)
		)
		(fill
			(color 0 0 0 0.0000)
		)
		(property "Sheetname" "DDR3"
			(at 256.54 165.6584 0)
			(effects
				(font
					(size 1.27 1.27)
				)
				(justify left bottom)
			)
		)
		(property "Sheetfile" "ddr3.kicad_sch"
			(at 256.54 185.3696 0)
			(effects
				(font
					(size 1.27 1.27)
				)
				(justify left top)
			)
		)
		(instances
			(project "artix-dc-scm"
				(path ""
					(page "9")
				)
			)
		)
	)
	(sheet
		(at 81.28 166.37)
		(size 25.4 17.78)
		(exclude_from_sim no)
		(in_bom yes)
		(on_board yes)
		(dnp no)
		(fields_autoplaced yes)
		(stroke
			(width 0)
			(type solid)
		)
		(fill
			(color 0 0 0 0.0000)
		)
		(property "Sheetname" "Ethernet"
			(at 81.28 165.6584 0)
			(effects
				(font
					(size 1.27 1.27)
				)
				(justify left bottom)
			)
		)
		(property "Sheetfile" "ethernet.kicad_sch"
			(at 81.28 185.3696 0)
			(effects
				(font
					(size 1.27 1.27)
				)
				(justify left top)
			)
		)
		(instances
			(project "artix-dc-scm"
				(path ""
					(page "2")
				)
			)
		)
	)
	(sheet
		(at 220.98 166.37)
		(size 27.94 19.05)
		(exclude_from_sim no)
		(in_bom yes)
		(on_board yes)
		(dnp no)
		(fields_autoplaced yes)
		(stroke
			(width 0)
			(type solid)
		)
		(fill
			(color 0 0 0 0.0000)
		)
		(property "Sheetname" "Interfaces"
			(at 220.98 165.6584 0)
			(effects
				(font
					(size 1.27 1.27)
				)
				(justify left bottom)
			)
		)
		(property "Sheetfile" "interfaces.kicad_sch"
			(at 220.98 186.0046 0)
			(effects
				(font
					(size 1.27 1.27)
				)
				(justify left top)
			)
		)
		(instances
			(project "artix-dc-scm"
				(path ""
					(page "8")
				)
			)
		)
	)
	(sheet
		(at 149.86 166.37)
		(size 27.94 19.05)
		(exclude_from_sim no)
		(in_bom yes)
		(on_board yes)
		(dnp no)
		(fields_autoplaced yes)
		(stroke
			(width 0)
			(type solid)
		)
		(fill
			(color 0 0 0 0.0000)
		)
		(property "Sheetname" "RoT"
			(at 149.86 165.6584 0)
			(effects
				(font
					(size 1.27 1.27)
				)
				(justify left bottom)
			)
		)
		(property "Sheetfile" "rot.kicad_sch"
			(at 149.86 186.0046 0)
			(effects
				(font
					(size 1.27 1.27)
				)
				(justify left top)
			)
		)
		(instances
			(project "artix-dc-scm"
				(path ""
					(page "6")
				)
			)
		)
	)
	(sheet
		(at 185.42 166.37)
		(size 29.21 17.78)
		(exclude_from_sim no)
		(in_bom yes)
		(on_board yes)
		(dnp no)
		(fields_autoplaced yes)
		(stroke
			(width 0)
			(type solid)
		)
		(fill
			(color 0 0 0 0.0000)
		)
		(property "Sheetname" "Edge connector"
			(at 185.42 165.6584 0)
			(effects
				(font
					(size 1.27 1.27)
				)
				(justify left bottom)
			)
		)
		(property "Sheetfile" "edge-connector.kicad_sch"
			(at 185.42 185.3696 0)
			(effects
				(font
					(size 1.27 1.27)
				)
				(justify left top)
			)
		)
		(instances
			(project "artix-dc-scm"
				(path ""
					(page "7")
				)
			)
		)
	)
	(sheet
		(at 181.61 196.85)
		(size 38.1 25.4)
		(exclude_from_sim no)
		(in_bom yes)
		(on_board yes)
		(dnp no)
		(fields_autoplaced yes)
		(stroke
			(width 0.1524)
			(type solid)
		)
		(fill
			(color 0 0 0 0.0000)
		)
		(property "Sheetname" "FPGA banks 34-35 & CFG"
			(at 181.61 196.1384 0)
			(effects
				(font
					(size 1.27 1.27)
				)
				(justify left bottom)
			)
		)
		(property "Sheetfile" "fpga-banks-34-25-cfg.kicad_sch"
			(at 181.61 222.8346 0)
			(effects
				(font
					(size 1.27 1.27)
				)
				(justify left top)
			)
		)
		(instances
			(project "artix-dc-scm"
				(path ""
					(page "11")
				)
			)
		)
	)
	(sheet_instances
		(path "/"
			(page "1")
		)
	)
)
